# BASEBOARD_FAB2 (Tioga Pass) — schematic netlist excerpt (pin names and nets, part order shuffled) for the footprints in the layout excerpt that follows; sources: Cadence DE-HDL packaged netlist, KiCad conversion of Wiwynn_Tioga_Pass_MB.brd

C7A36  CAP_A  22.0UF 4V 20% X6S  pkg 0603V  page 132 : A = PVNN_PCH_STBY ; B = GND
C9M5  CAP_A  0.1UF 16V 10% X7R  pkg 0402V  page 161 : A = P12V_FAN ; B = GND
R7G16  RES  0.0 5% EMPTY  pkg 0402  page 189 : A = JTAG_PCH_GBE_TDO ; B = JTAG_TDO

(kicad_pcb
	(version 20260206)
	(generator "pcbnew")
	(generator_version "10.0")
	(general
		(thickness 1.6)
		(legacy_teardrops no)
	)
	(paper "A4")
	(title_block
		(title "Wiwynn_Tioga_Pass_MB.brd")
		(comment 1 "Tioga Pass / footprints 605-607 of 4770")
	)
	(layers
		(0 "F.Cu" signal "TOP")
		(4 "In1.Cu" signal "L2GND")
		(6 "In2.Cu" signal "L3")
		(8 "In3.Cu" signal "L4GND")
		(10 "In4.Cu" signal "L5")
		(12 "In5.Cu" signal "L6GND")
		(14 "In6.Cu" signal "L7VCC")
		(16 "In7.Cu" signal "L8VCC")
		(18 "In8.Cu" signal "L9GND")
		(20 "In9.Cu" signal "L10")
		(22 "In10.Cu" signal "L11GND")
		(24 "In11.Cu" signal "L12")
		(26 "In12.Cu" signal "L13GND")
		(2 "B.Cu" signal "BOTTOM")
		(9 "F.Adhes" user "F.Adhesive")
		(11 "B.Adhes" user "B.Adhesive")
		(13 "F.Paste" user "Package Geometry/Pastemask Top")
		(15 "B.Paste" user "Package Geometry/Pastemask Bottom")
		(5 "F.SilkS" user "Ref Des/Silkscreen Top")
		(7 "B.SilkS" user "Ref Des/Silkscreen Bottom")
		(1 "F.Mask" user "Board Geometry/Soldermask Top")
		(3 "B.Mask" user "Board Geometry/Soldermask Bottom")
		(17 "Dwgs.User" user "User.Drawings")
		(19 "Cmts.User" user "User.Comments")
		(21 "Eco1.User" user "User.Eco1")
		(23 "Eco2.User" user "User.Eco2")
		(25 "Edge.Cuts" user "Board Geometry/Outline")
		(27 "Margin" user)
		(31 "F.CrtYd" user "Package Geometry/Place Bound Top")
		(29 "B.CrtYd" user "Package Geometry/Place Bound Bottom")
		(35 "F.Fab" user "Ref Des/Assembly Top")
		(33 "B.Fab" user "Ref Des/Assembly Bottom")
	)
	(footprint ""
		(layer "F.Cu")
		(at 377.8123 -137.1092)
		(property "Reference" "C7A36"
			(at 0 0 0)
			(layer "F.SilkS")
			(hide yes)
			(effects
				(font
					(size 1.27 1.27)
				)
			)
		)
		(property "Value" ""
			(at 0 0 0)
			(layer "F.Fab")
			(effects
				(font
					(size 1.27 1.27)
				)
			)
		)
		(duplicate_pad_numbers_are_jumpers no)
		(fp_rect
			(start -0.4953 1.6002)
			(end 0.4953 -0.2032)
			(stroke
				(width 0)
				(type default)
			)
			(fill no)
			(layer "F.CrtYd")
		)
		(fp_line
			(start -0.4953 -0.2032)
			(end 0.4953 -0.2032)
			(stroke
				(width 0.1)
				(type default)
			)
			(layer "F.Fab")
		)
		(fp_line
			(start -0.4953 1.6002)
			(end -0.4953 -0.2032)
			(stroke
				(width 0.1)
				(type default)
			)
			(layer "F.Fab")
		)
		(fp_line
			(start 0.4953 -0.2032)
			(end 0.4953 1.6002)
			(stroke
				(width 0.1)
				(type default)
			)
			(layer "F.Fab")
		)
		(fp_line
			(start 0.4953 1.6002)
			(end -0.4953 1.6002)
			(stroke
				(width 0.1)
				(type default)
			)
			(layer "F.Fab")
		)
		(pad "1" smd rect
			(at 0 0)
			(size 0.762 0.889)
			(layers "F.Cu" "F.Mask" "F.Paste")
			(net "PVNN_PCH_STBY")
		)
		(pad "2" smd rect
			(at 0 1.397)
			(size 0.762 0.889)
			(layers "F.Cu" "F.Mask" "F.Paste")
			(net "GND")
		)
		(zone
			(layer "F.Cu")
			(hatch none 0.5)
			(connect_pads
				(clearance 0)
			)
			(min_thickness 0.25)
			(keepout
				(tracks not_allowed)
				(vias allowed)
				(pads allowed)
				(copperpour not_allowed)
				(footprints allowed)
			)
			(placement
				(enabled no)
				(sheetname "")
			)
			(fill
				(thermal_gap 0.5)
				(thermal_bridge_width 0.5)
				(island_removal_mode 0)
			)
			(polygon
				(pts
					(xy 377.4313 -136.1567) (xy 378.1933 -136.1567) (xy 378.1933 -136.6647) (xy 377.4313 -136.6647)
				)
			)
		)
	)
	(footprint ""
		(layer "F.Cu")
		(at 7.665212 -108.42117 90)
		(property "Reference" "C9M5"
			(at 0 0 90)
			(layer "F.SilkS")
			(hide yes)
			(effects
				(font
					(size 1.27 1.27)
				)
			)
		)
		(property "Value" ""
			(at 0 0 90)
			(layer "F.Fab")
			(effects
				(font
					(size 1.27 1.27)
				)
			)
		)
		(duplicate_pad_numbers_are_jumpers no)
		(fp_poly
			(pts
				(xy 0.3048 -0.1016) (xy 0.3048 0.9906) (xy -0.3048 0.9906) (xy -0.3048 -0.1016)
			)
			(stroke
				(width 0)
				(type default)
			)
			(fill no)
			(layer "F.CrtYd")
		)
		(fp_line
			(start 0.3048 -0.1016)
			(end -0.3048 -0.1016)
			(stroke
				(width 0.1)
				(type default)
			)
			(layer "F.Fab")
		)
		(fp_line
			(start -0.3048 -0.1016)
			(end -0.3048 0.9906)
			(stroke
				(width 0.1)
				(type default)
			)
			(layer "F.Fab")
		)
		(fp_line
			(start 0.3048 0.9906)
			(end 0.3048 -0.1016)
			(stroke
				(width 0.1)
				(type default)
			)
			(layer "F.Fab")
		)
		(fp_line
			(start -0.3048 0.9906)
			(end 0.3048 0.9906)
			(stroke
				(width 0.1)
				(type default)
			)
			(layer "F.Fab")
		)
		(pad "1" smd rect
			(at 0 0 90)
			(size 0.508 0.508)
			(layers "F.Cu" "F.Mask" "F.Paste")
			(net "P12V_FAN")
		)
		(pad "2" smd rect
			(at 0 0.889 90)
			(size 0.508 0.508)
			(layers "F.Cu" "F.Mask" "F.Paste")
			(net "GND")
		)
		(zone
			(layer "F.Cu")
			(hatch none 0.5)
			(connect_pads
				(clearance 0)
			)
			(min_thickness 0.25)
			(keepout
				(tracks allowed)
				(vias not_allowed)
				(pads allowed)
				(copperpour not_allowed)
				(footprints allowed)
			)
			(placement
				(enabled no)
				(sheetname "")
			)
			(fill
				(thermal_gap 0.5)
				(thermal_bridge_width 0.5)
				(island_removal_mode 0)
			)
			(polygon
				(pts
					(xy 7.919212 -108.16717) (xy 7.919212 -108.67517) (xy 8.300212 -108.67517) (xy 8.300212 -108.16717)
				)
			)
		)
		(zone
			(layer "F.Cu")
			(hatch none 0.5)
			(connect_pads
				(clearance 0)
			)
			(min_thickness 0.25)
			(keepout
				(tracks not_allowed)
				(vias allowed)
				(pads allowed)
				(copperpour not_allowed)
				(footprints allowed)
			)
			(placement
				(enabled no)
				(sheetname "")
			)
			(fill
				(thermal_gap 0.5)
				(thermal_bridge_width 0.5)
				(island_removal_mode 0)
			)
			(polygon
				(pts
					(xy 8.300212 -108.16717) (xy 8.300212 -108.67517) (xy 7.919212 -108.67517) (xy 7.919212 -108.16717)
				)
			)
		)
	)
	(footprint ""
		(layer "F.Cu")
		(at 385.2926 -0.254)
		(property "Reference" "R7G16"
			(at 0 0 0)
			(layer "F.SilkS")
			(hide yes)
			(effects
				(font
					(size 1.27 1.27)
				)
			)
		)
		(property "Value" ""
			(at 0 0 0)
			(layer "F.Fab")
			(effects
				(font
					(size 1.27 1.27)
				)
			)
		)
		(duplicate_pad_numbers_are_jumpers no)
		(fp_poly
			(pts
				(xy -0.2794 -0.1016) (xy 0.2794 -0.1016) (xy 0.2794 0.9906) (xy -0.2794 0.9906)
			)
			(stroke
				(width 0)
				(type default)
			)
			(fill no)
			(layer "F.CrtYd")
		)
		(fp_line
			(start -0.2794 -0.1016)
			(end -0.2794 0.9906)
			(stroke
				(width 0.1)
				(type default)
			)
			(layer "F.Fab")
		)
		(fp_line
			(start -0.2794 0.9906)
			(end 0.2794 0.9906)
			(stroke
				(width 0.1)
				(type default)
			)
			(layer "F.Fab")
		)
		(fp_line
			(start 0.2794 -0.1016)
			(end -0.2794 -0.1016)
			(stroke
				(width 0.1)
				(type default)
			)
			(layer "F.Fab")
		)
		(fp_line
			(start 0.2794 0.9906)
			(end 0.2794 -0.1016)
			(stroke
				(width 0.1)
				(type default)
			)
			(layer "F.Fab")
		)
		(pad "1" smd rect
			(at 0 0)
			(size 0.508 0.508)
			(layers "F.Cu" "F.Mask" "F.Paste")
			(net "JTAG_PCH_GBE_TDO")
		)
		(pad "2" smd rect
			(at 0 0.889)
			(size 0.508 0.508)
			(layers "F.Cu" "F.Mask" "F.Paste")
			(net "JTAG_TDO")
		)
		(zone
			(layer "F.Cu")
			(hatch none 0.5)
			(connect_pads
				(clearance 0)
			)
			(min_thickness 0.25)
			(keepout
				(tracks allowed)
				(vias not_allowed)
				(pads allowed)
				(copperpour not_allowed)
				(footprints allowed)
			)
			(placement
				(enabled no)
				(sheetname "")
			)
			(fill
				(thermal_gap 0.5)
				(thermal_bridge_width 0.5)
				(island_removal_mode 0)
			)
			(polygon
				(pts
					(xy 385.0386 0) (xy 385.5466 0) (xy 385.5466 0.381) (xy 385.0386 0.381)
				)
			)
		)
		(zone
			(layer "F.Cu")
			(hatch none 0.5)
			(connect_pads
				(clearance 0)
			)
			(min_thickness 0.25)
			(keepout
				(tracks not_allowed)
				(vias allowed)
				(pads allowed)
				(copperpour not_allowed)
				(footprints allowed)
			)
			(placement
				(enabled no)
				(sheetname "")
			)
			(fill
				(thermal_gap 0.5)
				(thermal_bridge_width 0.5)
				(island_removal_mode 0)
			)
			(polygon
				(pts
					(xy 385.0386 0.381) (xy 385.5466 0.381) (xy 385.5466 0) (xy 385.0386 0)
				)
			)
		)
	)
)
